(kicad_pcb
	(version 20241229)
	(generator "pcbnew")
	(generator_version "9.0")
	(general
		(thickness 1.61)
		(legacy_teardrops no)
	)
	(paper "A3")
	(title_block
		(title "SO-DIMM DDR5 Tester")
		(date "2025-11-26")
		(rev "1.3.0")
		(comment 9 "footprints 424-430 of 627")
	)
	(layers
		(0 "F.Cu" signal)
		(4 "In1.Cu" power)
		(6 "In2.Cu" mixed)
		(8 "In3.Cu" power)
		(10 "In4.Cu" mixed)
		(12 "In5.Cu" power)
		(14 "In6.Cu" mixed)
		(16 "In7.Cu" power)
		(18 "In8.Cu" power)
		(20 "In9.Cu" mixed)
		(22 "In10.Cu" power)
		(2 "B.Cu" signal)
		(9 "F.Adhes" user "F.Adhesive")
		(11 "B.Adhes" user "B.Adhesive")
		(13 "F.Paste" user)
		(15 "B.Paste" user)
		(5 "F.SilkS" user "F.Silkscreen")
		(7 "B.SilkS" user "B.Silkscreen")
		(1 "F.Mask" user)
		(3 "B.Mask" user)
		(17 "Dwgs.User" user "User.Drawings")
		(19 "Cmts.User" user "User.Comments")
		(21 "Eco1.User" user "User.Eco1")
		(23 "Eco2.User" user "User.Eco2")
		(25 "Edge.Cuts" user)
		(27 "Margin" user)
		(31 "F.CrtYd" user "F.Courtyard")
		(29 "B.CrtYd" user "B.Courtyard")
		(35 "F.Fab" user)
		(33 "B.Fab" user)
	)
	(footprint "antmicro-footprints:R_0402_1005Metric"
		(layer "B.Cu")
		(at 147.877001 177.3025)
		(descr "Resistor SMD 0402 (1005 Metric), square (rectangular) end terminal, IPC_7351 nominal, (Body size source: IPC-SM-782 page 76, https://www.pcb-3d.com/wordpress/wp-content/uploads/ipc-sm-782a_amendment_1_and_2.pdf)")
		(tags "resistor 0402")
		(property "Reference" "R39"
			(at 0 1.17 180)
			(layer "B.SilkS")
			(hide yes)
			(effects
				(font
					(size 0.7 0.7)
					(thickness 0.15)
				)
				(justify left bottom mirror)
			)
		)
		(property "Value" "R_100R_0402"
			(at 0 -1.169 180)
			(layer "B.Fab")
			(effects
				(font
					(size 0.7 0.7)
					(thickness 0.15)
				)
				(justify left bottom mirror)
			)
		)
		(property "Datasheet" "https://www.bourns.com/docs/product-datasheets/cr.pdf"
			(at 0 0 0)
			(layer "F.Fab")
			(hide yes)
			(effects
				(font
					(size 1.27 1.27)
					(thickness 0.15)
				)
			)
		)
		(property "Author" "Antmicro"
			(at 0 0 0)
			(layer "B.Fab")
			(hide yes)
			(effects
				(font
					(size 1 1)
					(thickness 0.15)
				)
				(justify mirror)
			)
		)
		(property "License" "Apache-2.0"
			(at 0 0 0)
			(layer "B.Fab")
			(hide yes)
			(effects
				(font
					(size 1 1)
					(thickness 0.15)
				)
				(justify mirror)
			)
		)
		(property "MPN" "CR0402-FX-1000GLF"
			(at 0 0 0)
			(layer "B.Fab")
			(hide yes)
			(effects
				(font
					(size 1 1)
					(thickness 0.15)
				)
				(justify mirror)
			)
		)
		(property "Manufacturer" "Bourns"
			(at 0 0 0)
			(layer "B.Fab")
			(hide yes)
			(effects
				(font
					(size 1 1)
					(thickness 0.15)
				)
				(justify mirror)
			)
		)
		(property "Tolerance" "1%"
			(at 0 0 0)
			(layer "B.Fab")
			(hide yes)
			(effects
				(font
					(size 1 1)
					(thickness 0.15)
				)
				(justify mirror)
			)
		)
		(property "Val" "100R"
			(at 0 0 0)
			(layer "B.Fab")
			(hide yes)
			(effects
				(font
					(size 1 1)
					(thickness 0.15)
				)
				(justify mirror)
			)
		)
		(sheetname "/FPGA power/")
		(sheetfile "fpga-power.kicad_sch")
		(attr smd)
		(fp_line
			(start -0.95 -0.45)
			(end -0.95 0.46)
			(stroke
				(width 0.05)
				(type solid)
			)
			(layer "B.CrtYd")
		)
		(fp_line
			(start -0.95 0.46)
			(end 0.9652 0.46)
			(stroke
				(width 0.05)
				(type solid)
			)
			(layer "B.CrtYd")
		)
		(fp_line
			(start 0.9652 -0.45)
			(end -0.95 -0.45)
			(stroke
				(width 0.05)
				(type solid)
			)
			(layer "B.CrtYd")
		)
		(fp_line
			(start 0.9652 0.46)
			(end 0.9652 -0.45)
			(stroke
				(width 0.05)
				(type solid)
			)
			(layer "B.CrtYd")
		)
		(fp_line
			(start -0.5 -0.249)
			(end -0.5 0.25)
			(stroke
				(width 0.15)
				(type solid)
			)
			(layer "B.Fab")
		)
		(fp_line
			(start -0.5 0.25)
			(end 0.499 0.25)
			(stroke
				(width 0.15)
				(type solid)
			)
			(layer "B.Fab")
		)
		(fp_line
			(start 0.499 -0.249)
			(end -0.5 -0.249)
			(stroke
				(width 0.15)
				(type solid)
			)
			(layer "B.Fab")
		)
		(fp_line
			(start 0.499 0.25)
			(end 0.499 -0.249)
			(stroke
				(width 0.15)
				(type solid)
			)
			(layer "B.Fab")
		)
		(pad "1" smd roundrect
			(at -0.5 0 270)
			(size 0.6 0.6)
			(layers "B.Cu" "B.Mask" "B.Paste")
			(roundrect_rratio 0.25)
			(net 369 "Net-(U4J-MGTRREF_115)")
			(pintype "passive")
		)
		(pad "2" smd roundrect
			(at 0.499 0)
			(size 0.6 0.6)
			(layers "B.Cu" "B.Mask" "B.Paste")
			(roundrect_rratio 0.25)
			(net 226 "+1V2_MGTAVTT")
			(pintype "passive")
		)
	)
	(footprint "antmicro-footprints:TP_SMD_1mm"
		(layer "B.Cu")
		(at 124.2 186.2 180)
		(property "Reference" "TP23"
			(at 0 0.731898 0)
			(layer "B.SilkS")
			(hide yes)
			(effects
				(font
					(size 0.7 0.7)
					(thickness 0.15)
				)
				(justify left bottom mirror)
			)
		)
		(property "Value" "TP_1mm_SMD"
			(at 0 -1.4 0)
			(layer "B.Fab")
			(effects
				(font
					(size 0.7 0.7)
					(thickness 0.15)
				)
				(justify left bottom mirror)
			)
		)
		(property "Author" "Antmicro"
			(at 248.4 372.4 0)
			(layer "B.Fab")
			(hide yes)
			(effects
				(font
					(size 1 1)
					(thickness 0.15)
				)
				(justify mirror)
			)
		)
		(property "License" "Apache-2.0"
			(at 248.4 372.4 0)
			(layer "B.Fab")
			(hide yes)
			(effects
				(font
					(size 1 1)
					(thickness 0.15)
				)
				(justify mirror)
			)
		)
		(property "MPN" ""
			(at 248.4 372.4 0)
			(layer "B.Fab")
			(hide yes)
			(effects
				(font
					(size 1 1)
					(thickness 0.15)
				)
				(justify mirror)
			)
		)
		(property "Manufacturer" ""
			(at 248.4 372.4 0)
			(layer "B.Fab")
			(hide yes)
			(effects
				(font
					(size 1 1)
					(thickness 0.15)
				)
				(justify mirror)
			)
		)
		(sheetname "/FPGA bank 14/")
		(sheetfile "fpga-bank-14.kicad_sch")
		(attr exclude_from_pos_files)
		(pad "1" smd circle
			(at 0 0 180)
			(size 1 1)
			(layers "B.Cu" "B.Mask")
			(net 612 "/FPGA bank 14/PUDC_B")
			(pinfunction "1")
			(pintype "passive")
		)
	)
	(footprint "antmicro-footprints:TP_SMD_1mm"
		(layer "B.Cu")
		(at 110 181.63 180)
		(property "Reference" "TP52"
			(at -3.2 -0.37 0)
			(layer "B.SilkS")
			(effects
				(font
					(size 0.7 0.7)
					(thickness 0.15)
				)
				(justify left bottom mirror)
			)
		)
		(property "Value" "TP_1mm_SMD"
			(at 0 -1.4 0)
			(layer "B.Fab")
			(effects
				(font
					(size 0.7 0.7)
					(thickness 0.15)
				)
				(justify left bottom mirror)
			)
		)
		(property "MPN" ""
			(at 0 0 0)
			(unlocked yes)
			(layer "B.Fab")
			(hide yes)
			(effects
				(font
					(size 1 1)
					(thickness 0.15)
				)
				(justify mirror)
			)
		)
		(property "Manufacturer" ""
			(at 0 0 0)
			(unlocked yes)
			(layer "B.Fab")
			(hide yes)
			(effects
				(font
					(size 1 1)
					(thickness 0.15)
				)
				(justify mirror)
			)
		)
		(property "Author" "Antmicro"
			(at 0 0 0)
			(unlocked yes)
			(layer "B.Fab")
			(hide yes)
			(effects
				(font
					(size 1 1)
					(thickness 0.15)
				)
				(justify mirror)
			)
		)
		(property "License" "Apache-2.0"
			(at 0 0 0)
			(unlocked yes)
			(layer "B.Fab")
			(hide yes)
			(effects
				(font
					(size 1 1)
					(thickness 0.15)
				)
				(justify mirror)
			)
		)
		(sheetname "/Debug FTDI/")
		(sheetfile "debug-ftdi.kicad_sch")
		(attr exclude_from_pos_files)
		(fp_circle
			(center 0 0)
			(end 0.6 0)
			(stroke
				(width 0.05)
				(type default)
			)
			(fill no)
			(layer "B.CrtYd")
		)
		(fp_text user "License: Apache-2.0"
			(at -0.5 -5.2 0)
			(layer "B.Fab")
			(effects
				(font
					(size 0.7 0.7)
					(thickness 0.15)
				)
				(justify left bottom mirror)
			)
		)
		(fp_text user "Author: Antmicro"
			(at -0.5 -4 0)
			(layer "B.Fab")
			(effects
				(font
					(size 0.7 0.7)
					(thickness 0.15)
				)
				(justify left bottom mirror)
			)
		)
		(fp_text user "${REFERENCE}"
			(at -0.5 -2.8 0)
			(layer "B.Fab")
			(effects
				(font
					(size 0.7 0.7)
					(thickness 0.15)
				)
				(justify left bottom mirror)
			)
		)
		(pad "1" smd circle
			(at 0 0 180)
			(size 1 1)
			(layers "B.Cu" "B.Mask")
			(net 1 "GND")
			(pinfunction "1")
			(pintype "passive")
		)
	)
	(footprint "antmicro-footprints:C_0402_1005Metric"
		(layer "B.Cu")
		(at 144.875001 180.3025 180)
		(descr "Capacitor SMD 0402 (1005 Metric), square (rectangular) end terminal, IPC_7351 nominal, (Body size source: IPC-SM-782 page 76, https://www.pcb-3d.com/wordpress/wp-content/uploads/ipc-sm-782a_amendment_1_and_2.pdf)")
		(tags "capacitor 0402")
		(property "Reference" "C92"
			(at 0 1.17 0)
			(layer "B.SilkS")
			(hide yes)
			(effects
				(font
					(size 0.7 0.7)
					(thickness 0.15)
				)
				(justify left bottom mirror)
			)
		)
		(property "Value" "C_100n_0402"
			(at 0 -1.169 0)
			(layer "B.Fab")
			(effects
				(font
					(size 0.7 0.7)
					(thickness 0.15)
				)
				(justify left bottom mirror)
			)
		)
		(property "Datasheet" "https://www.murata.com/products/productdetail?partno=GRM155R61H104KE14%23"
			(at 0 0 180)
			(layer "F.Fab")
			(hide yes)
			(effects
				(font
					(size 1.27 1.27)
					(thickness 0.15)
				)
			)
		)
		(property "Author" "Antmicro"
			(at 289.750002 360.605 0)
			(layer "B.Fab")
			(hide yes)
			(effects
				(font
					(size 1 1)
					(thickness 0.15)
				)
				(justify mirror)
			)
		)
		(property "Dielectric" "X5R"
			(at 289.750002 360.605 0)
			(layer "B.Fab")
			(hide yes)
			(effects
				(font
					(size 1 1)
					(thickness 0.15)
				)
				(justify mirror)
			)
		)
		(property "License" "Apache-2.0"
			(at 289.750002 360.605 0)
			(layer "B.Fab")
			(hide yes)
			(effects
				(font
					(size 1 1)
					(thickness 0.15)
				)
				(justify mirror)
			)
		)
		(property "MPN" "GRM155R61H104KE14D"
			(at 289.750002 360.605 0)
			(layer "B.Fab")
			(hide yes)
			(effects
				(font
					(size 1 1)
					(thickness 0.15)
				)
				(justify mirror)
			)
		)
		(property "Manufacturer" "Murata"
			(at 289.750002 360.605 0)
			(layer "B.Fab")
			(hide yes)
			(effects
				(font
					(size 1 1)
					(thickness 0.15)
				)
				(justify mirror)
			)
		)
		(property "Val" "100n"
			(at 289.750002 360.605 0)
			(layer "B.Fab")
			(hide yes)
			(effects
				(font
					(size 1 1)
					(thickness 0.15)
				)
				(justify mirror)
			)
		)
		(property "Voltage" "50V"
			(at 289.750002 360.605 0)
			(layer "B.Fab")
			(hide yes)
			(effects
				(font
					(size 1 1)
					(thickness 0.15)
				)
				(justify mirror)
			)
		)
		(sheetname "/FPGA power/")
		(sheetfile "fpga-power.kicad_sch")
		(attr smd)
		(fp_rect
			(start -0.9656 0.4572)
			(end 0.9652 -0.4828)
			(stroke
				(width 0.05)
				(type solid)
			)
			(fill no)
			(layer "B.CrtYd")
		)
		(fp_line
			(start 0.498 0.25)
			(end 0.498 -0.248)
			(stroke
				(width 0.15)
				(type solid)
			)
			(layer "B.Fab")
		)
		(fp_line
			(start 0.498 -0.248)
			(end -0.5 -0.248)
			(stroke
				(width 0.15)
				(type solid)
			)
			(layer "B.Fab")
		)
		(fp_line
			(start -0.5 0.25)
			(end 0.498 0.25)
			(stroke
				(width 0.15)
				(type solid)
			)
			(layer "B.Fab")
		)
		(fp_line
			(start -0.5 -0.248)
			(end -0.5 0.25)
			(stroke
				(width 0.15)
				(type solid)
			)
			(layer "B.Fab")
		)
		(pad "1" smd roundrect
			(at -0.5 0 90)
			(size 0.6 0.6)
			(layers "B.Cu" "B.Mask" "B.Paste")
			(roundrect_rratio 0.25)
			(net 1 "GND")
			(pintype "passive")
		)
		(pad "2" smd roundrect
			(at 0.498 0 180)
			(size 0.6 0.6)
			(layers "B.Cu" "B.Mask" "B.Paste")
			(roundrect_rratio 0.25)
			(net 227 "+1V0")
			(pintype "passive")
		)
	)
	(footprint "antmicro-footprints:C_0402_1005Metric"
		(layer "B.Cu")
		(at 145.525501 204.800501 90)
		(descr "Capacitor SMD 0402")
		(tags "capacitor SMD 0402")
		(property "Reference" "C230"
			(at 0 0.699 270)
			(layer "B.SilkS")
			(hide yes)
			(effects
				(font
					(size 0.7 0.7)
					(thickness 0.15)
				)
				(justify left bottom mirror)
			)
		)
		(property "Value" "C_100n_0402"
			(at -1.022927 -2.155213 270)
			(layer "B.Fab")
			(effects
				(font
					(size 0.7 0.7)
					(thickness 0.15)
				)
				(justify left bottom mirror)
			)
		)
		(property "Datasheet" "https://www.murata.com/products/productdetail?partno=GRM155R61H104KE14%23"
			(at 0 0 90)
			(layer "F.Fab")
			(hide yes)
			(effects
				(font
					(size 1.27 1.27)
					(thickness 0.15)
				)
			)
		)
		(property "Author" "Antmicro"
			(at 350.326002 59.275 0)
			(layer "B.Fab")
			(hide yes)
			(effects
				(font
					(size 1 1)
					(thickness 0.15)
				)
				(justify mirror)
			)
		)
		(property "Dielectric" "X5R"
			(at 350.326002 59.275 0)
			(layer "B.Fab")
			(hide yes)
			(effects
				(font
					(size 1 1)
					(thickness 0.15)
				)
				(justify mirror)
			)
		)
		(property "License" "Apache-2.0"
			(at 350.326002 59.275 0)
			(layer "B.Fab")
			(hide yes)
			(effects
				(font
					(size 1 1)
					(thickness 0.15)
				)
				(justify mirror)
			)
		)
		(property "MPN" "GRM155R61H104KE14D"
			(at 350.326002 59.275 0)
			(layer "B.Fab")
			(hide yes)
			(effects
				(font
					(size 1 1)
					(thickness 0.15)
				)
				(justify mirror)
			)
		)
		(property "Manufacturer" "Murata"
			(at 350.326002 59.275 0)
			(layer "B.Fab")
			(hide yes)
			(effects
				(font
					(size 1 1)
					(thickness 0.15)
				)
				(justify mirror)
			)
		)
		(property "Val" "100n"
			(at 350.326002 59.275 0)
			(layer "B.Fab")
			(hide yes)
			(effects
				(font
					(size 1 1)
					(thickness 0.15)
				)
				(justify mirror)
			)
		)
		(property "Voltage" "50V"
			(at 350.326002 59.275 0)
			(layer "B.Fab")
			(hide yes)
			(effects
				(font
					(size 1 1)
					(thickness 0.15)
				)
				(justify mirror)
			)
		)
		(sheetname "/FPGA MGT Interface/")
		(sheetfile "fpga-mgt.kicad_sch")
		(attr smd)
		(fp_rect
			(start -0.9659 0.481258)
			(end 0.9649 -0.458742)
			(stroke
				(width 0.05)
				(type solid)
			)
			(fill no)
			(layer "B.CrtYd")
		)
		(fp_line
			(start 0.499 -0.248)
			(end -0.499 -0.248)
			(stroke
				(width 0.15)
				(type solid)
			)
			(layer "B.Fab")
		)
		(fp_line
			(start -0.499 -0.248)
			(end -0.499 0.25)
			(stroke
				(width 0.15)
				(type solid)
			)
			(layer "B.Fab")
		)
		(fp_line
			(start 0.499 0.25)
			(end 0.499 -0.248)
			(stroke
				(width 0.15)
				(type solid)
			)
			(layer "B.Fab")
		)
		(fp_line
			(start -0.499 0.25)
			(end 0.499 0.25)
			(stroke
				(width 0.15)
				(type solid)
			)
			(layer "B.Fab")
		)
		(pad "1" smd roundrect
			(at -0.484 0 90)
			(size 0.59 0.64)
			(layers "B.Cu" "B.Mask" "B.Paste")
			(roundrect_rratio 0.25)
			(net 24 "/FPGA MGT Interface/PCIE.TXD3_N")
			(pintype "passive")
		)
		(pad "2" smd roundrect
			(at 0.484 0 90)
			(size 0.59 0.64)
			(layers "B.Cu" "B.Mask" "B.Paste")
			(roundrect_rratio 0.25)
			(net 25 "/FPGA MGT Interface/GTX_TX0_N")
			(pintype "passive")
		)
	)
	(footprint "antmicro-footprints:TP_SMD_1mm"
		(layer "B.Cu")
		(at 90.1 186.1 180)
		(property "Reference" "TP47"
			(at -1.2 0.6 0)
			(layer "B.SilkS")
			(effects
				(font
					(size 0.7 0.7)
					(thickness 0.15)
				)
				(justify left bottom mirror)
			)
		)
		(property "Value" "TP_1mm_SMD"
			(at 0 -1.4 0)
			(layer "B.Fab")
			(effects
				(font
					(size 0.7 0.7)
					(thickness 0.15)
				)
				(justify left bottom mirror)
			)
		)
		(property "MPN" ""
			(at 0 0 0)
			(unlocked yes)
			(layer "B.Fab")
			(hide yes)
			(effects
				(font
					(size 1 1)
					(thickness 0.15)
				)
				(justify mirror)
			)
		)
		(property "Manufacturer" ""
			(at 0 0 0)
			(unlocked yes)
			(layer "B.Fab")
			(hide yes)
			(effects
				(font
					(size 1 1)
					(thickness 0.15)
				)
				(justify mirror)
			)
		)
		(property "Author" "Antmicro"
			(at 0 0 0)
			(unlocked yes)
			(layer "B.Fab")
			(hide yes)
			(effects
				(font
					(size 1 1)
					(thickness 0.15)
				)
				(justify mirror)
			)
		)
		(property "License" "Apache-2.0"
			(at 0 0 0)
			(unlocked yes)
			(layer "B.Fab")
			(hide yes)
			(effects
				(font
					(size 1 1)
					(thickness 0.15)
				)
				(justify mirror)
			)
		)
		(sheetname "/Debug FTDI/")
		(sheetfile "debug-ftdi.kicad_sch")
		(attr exclude_from_pos_files)
		(fp_circle
			(center 0 0)
			(end 0.6 0)
			(stroke
				(width 0.05)
				(type default)
			)
			(fill no)
			(layer "B.CrtYd")
		)
		(fp_text user "License: Apache-2.0"
			(at -0.5 -5.2 0)
			(layer "B.Fab")
			(effects
				(font
					(size 0.7 0.7)
					(thickness 0.15)
				)
				(justify left bottom mirror)
			)
		)
		(fp_text user "Author: Antmicro"
			(at -0.5 -4 0)
			(layer "B.Fab")
			(effects
				(font
					(size 0.7 0.7)
					(thickness 0.15)
				)
				(justify left bottom mirror)
			)
		)
		(fp_text user "${REFERENCE}"
			(at -0.5 -2.8 0)
			(layer "B.Fab")
			(effects
				(font
					(size 0.7 0.7)
					(thickness 0.15)
				)
				(justify left bottom mirror)
			)
		)
		(pad "1" smd circle
			(at 0 0 180)
			(size 1 1)
			(layers "B.Cu" "B.Mask")
			(net 1 "GND")
			(pinfunction "1")
			(pintype "passive")
		)
	)
	(footprint "antmicro-footprints:C_0402_1005Metric"
		(layer "B.Cu")
		(at 128.875501 168.301 180)
		(descr "Capacitor SMD 0402 (1005 Metric), square (rectangular) end terminal, IPC_7351 nominal, (Body size source: IPC-SM-782 page 76, https://www.pcb-3d.com/wordpress/wp-content/uploads/ipc-sm-782a_amendment_1_and_2.pdf)")
		(tags "capacitor 0402")
		(property "Reference" "C46"
			(at 0 1.17 0)
			(layer "B.SilkS")
			(hide yes)
			(effects
				(font
					(size 0.7 0.7)
					(thickness 0.15)
				)
				(justify left bottom mirror)
			)
		)
		(property "Value" "C_100n_0402"
			(at 0 -1.169 0)
			(layer "B.Fab")
			(effects
				(font
					(size 0.7 0.7)
					(thickness 0.15)
				)
				(justify left bottom mirror)
			)
		)
		(property "Datasheet" "https://www.murata.com/products/productdetail?partno=GRM155R61H104KE14%23"
			(at 0 0 180)
			(layer "F.Fab")
			(hide yes)
			(effects
				(font
					(size 1.27 1.27)
					(thickness 0.15)
				)
			)
		)
		(property "Author" "Antmicro"
			(at 257.751002 336.602 0)
			(layer "B.Fab")
			(hide yes)
			(effects
				(font
					(size 1 1)
					(thickness 0.15)
				)
				(justify mirror)
			)
		)
		(property "Dielectric" "X5R"
			(at 257.751002 336.602 0)
			(layer "B.Fab")
			(hide yes)
			(effects
				(font
					(size 1 1)
					(thickness 0.15)
				)
				(justify mirror)
			)
		)
		(property "License" "Apache-2.0"
			(at 257.751002 336.602 0)
			(layer "B.Fab")
			(hide yes)
			(effects
				(font
					(size 1 1)
					(thickness 0.15)
				)
				(justify mirror)
			)
		)
		(property "MPN" "GRM155R61H104KE14D"
			(at 257.751002 336.602 0)
			(layer "B.Fab")
			(hide yes)
			(effects
				(font
					(size 1 1)
					(thickness 0.15)
				)
				(justify mirror)
			)
		)
		(property "Manufacturer" "Murata"
			(at 257.751002 336.602 0)
			(layer "B.Fab")
			(hide yes)
			(effects
				(font
					(size 1 1)
					(thickness 0.15)
				)
				(justify mirror)
			)
		)
		(property "Val" "100n"
			(at 257.751002 336.602 0)
			(layer "B.Fab")
			(hide yes)
			(effects
				(font
					(size 1 1)
					(thickness 0.15)
				)
				(justify mirror)
			)
		)
		(property "Voltage" "50V"
			(at 257.751002 336.602 0)
			(layer "B.Fab")
			(hide yes)
			(effects
				(font
					(size 1 1)
					(thickness 0.15)
				)
				(justify mirror)
			)
		)
		(sheetname "/FPGA power/")
		(sheetfile "fpga-power.kicad_sch")
		(attr smd)
		(fp_rect
			(start -0.9656 0.4572)
			(end 0.9652 -0.4828)
			(stroke
				(width 0.05)
				(type solid)
			)
			(fill no)
			(layer "B.CrtYd")
		)
		(fp_line
			(start 0.498 0.25)
			(end 0.498 -0.248)
			(stroke
				(width 0.15)
				(type solid)
			)
			(layer "B.Fab")
		)
		(fp_line
			(start 0.498 -0.248)
			(end -0.5 -0.248)
			(stroke
				(width 0.15)
				(type solid)
			)
			(layer "B.Fab")
		)
		(fp_line
			(start -0.5 0.25)
			(end 0.498 0.25)
			(stroke
				(width 0.15)
				(type solid)
			)
			(layer "B.Fab")
		)
		(fp_line
			(start -0.5 -0.248)
			(end -0.5 0.25)
			(stroke
				(width 0.15)
				(type solid)
			)
			(layer "B.Fab")
		)
		(pad "1" smd roundrect
			(at -0.5 0 90)
			(size 0.6 0.6)
			(layers "B.Cu" "B.Mask" "B.Paste")
			(roundrect_rratio 0.25)
			(net 1 "GND")
			(pintype "passive")
		)
		(pad "2" smd roundrect
			(at 0.498 0 180)
			(size 0.6 0.6)
			(layers "B.Cu" "B.Mask" "B.Paste")
			(roundrect_rratio 0.25)
			(net 200 "+3V3")
			(pintype "passive")
		)
	)
)
